(kicad_pcb
	(version 20260206)
	(generator "pcbnew")
	(generator_version "10.0")
	(general
		(thickness 1.6)
		(legacy_teardrops no)
	)
	(paper "A4")
	(title_block
		(title "baseboard — 13948-1b.1110WZS1818.brd")
		(comment 1 "Honey Badger (Wiwynn) / footprints 1326-1334 of 2523")
	)
	(layers
		(0 "F.Cu" signal "TOP")
		(4 "In1.Cu" signal "L2GND")
		(6 "In2.Cu" signal "L3")
		(8 "In3.Cu" signal "L4VCC")
		(10 "In4.Cu" signal "L5VCC")
		(12 "In5.Cu" signal "L6")
		(14 "In6.Cu" signal "L7GND")
		(2 "B.Cu" signal "BOTTOM")
		(9 "F.Adhes" user "F.Adhesive")
		(11 "B.Adhes" user "B.Adhesive")
		(13 "F.Paste" user "Package Geometry/Pastemask Top")
		(15 "B.Paste" user "Package Geometry/Pastemask Bottom")
		(5 "F.SilkS" user "Ref Des/Silkscreen Top")
		(7 "B.SilkS" user "Ref Des/Silkscreen Bottom")
		(1 "F.Mask" user "Board Geometry/Soldermask Top")
		(3 "B.Mask" user "Board Geometry/Soldermask Bottom")
		(17 "Dwgs.User" user "User.Drawings")
		(19 "Cmts.User" user "User.Comments")
		(21 "Eco1.User" user "User.Eco1")
		(23 "Eco2.User" user "User.Eco2")
		(25 "Edge.Cuts" user "Board Geometry/Outline")
		(27 "Margin" user)
		(31 "F.CrtYd" user "Package Geometry/Place Bound Top")
		(29 "B.CrtYd" user "Package Geometry/Place Bound Bottom")
		(35 "F.Fab" user "Ref Des/Assembly Top")
		(33 "B.Fab" user "Ref Des/Assembly Bottom")
	)
	(footprint ""
		(layer "F.Cu")
		(at 88.392 -18.669 180)
		(property "Reference" "PC218"
			(at 0 0 180)
			(layer "F.SilkS")
			(hide yes)
			(effects
				(font
					(size 1.27 1.27)
				)
			)
		)
		(property "Value" "SCD01U50V3KX-4GP"
			(at 0 -2.8194 180)
			(unlocked yes)
			(layer "F.Fab")
			(hide yes)
			(effects
				(font
					(size 1.016 1.016)
					(thickness 0.1524)
				)
			)
		)
		(property "Device Type" "C603H36"
			(at 0 -4.3434 180)
			(unlocked yes)
			(layer "F.Fab")
			(hide yes)
			(effects
				(font
					(size 1.016 1.016)
					(thickness 0.1524)
				)
			)
		)
		(duplicate_pad_numbers_are_jumpers no)
		(fp_line
			(start 0.508 0)
			(end -0.508 0)
			(stroke
				(width 0.2032)
				(type default)
			)
			(layer "F.SilkS")
		)
		(fp_rect
			(start -0.5842 1.3335)
			(end 0.5842 -1.3335)
			(stroke
				(width 0)
				(type default)
			)
			(fill no)
			(layer "F.CrtYd")
		)
		(fp_rect
			(start -0.5842 1.3335)
			(end 0.5842 -1.3335)
			(stroke
				(width 0)
				(type default)
			)
			(fill no)
			(layer "F.Fab")
		)
		(pad "1" smd custom
			(at 0 -0.762 180)
			(size 0.2159 0.2159)
			(layers "F.Cu" "F.Mask" "F.Paste")
			(net "VT235_VDES")
			(options
				(clearance outline)
				(anchor circle)
			)
			(primitives
				(gr_poly
					(pts
						(arc
							(start -0.3302 -0.4318)
							(mid -0.402042 -0.402042)
							(end -0.4318 -0.3302)
						)
						(arc
							(start -0.4318 0.3302)
							(mid -0.402042 0.402042)
							(end -0.3302 0.4318)
						)
						(arc
							(start 0.3302 0.4318)
							(mid 0.402042 0.402042)
							(end 0.4318 0.3302)
						)
						(arc
							(start 0.4318 -0.3302)
							(mid 0.402042 -0.402042)
							(end 0.3302 -0.4318)
						)
					)
					(width 0)
					(fill yes)
				)
			)
		)
		(pad "2" smd custom
			(at 0 0.762 180)
			(size 0.2159 0.2159)
			(layers "F.Cu" "F.Mask" "F.Paste")
			(net "VT235_VDES_RCC")
			(options
				(clearance outline)
				(anchor circle)
			)
			(primitives
				(gr_poly
					(pts
						(arc
							(start -0.3302 -0.4318)
							(mid -0.402042 -0.402042)
							(end -0.4318 -0.3302)
						)
						(arc
							(start -0.4318 0.3302)
							(mid -0.402042 0.402042)
							(end -0.3302 0.4318)
						)
						(arc
							(start 0.3302 0.4318)
							(mid 0.402042 0.402042)
							(end 0.4318 0.3302)
						)
						(arc
							(start 0.4318 -0.3302)
							(mid 0.402042 -0.402042)
							(end 0.3302 -0.4318)
						)
					)
					(width 0)
					(fill yes)
				)
			)
		)
	)
	(footprint ""
		(layer "F.Cu")
		(at 112.40897 -114.3 180)
		(property "Reference" "SC1078"
			(at 0 0 180)
			(layer "F.SilkS")
			(hide yes)
			(effects
				(font
					(size 1.27 1.27)
				)
			)
		)
		(property "Value" "SCD01U10V1KX-GP"
			(at -2.8321 -1.7399 180)
			(unlocked yes)
			(layer "F.Fab")
			(hide yes)
			(effects
				(font
					(size 1.016 1.016)
					(thickness 0.1524)
				)
			)
		)
		(property "Device Type" "C0201H13"
			(at -2.8321 -3.2639 180)
			(unlocked yes)
			(layer "F.Fab")
			(hide yes)
			(effects
				(font
					(size 1.016 1.016)
					(thickness 0.1524)
				)
			)
		)
		(duplicate_pad_numbers_are_jumpers no)
		(fp_rect
			(start -0.2794 0.6477)
			(end 0.2794 -0.6477)
			(stroke
				(width 0)
				(type default)
			)
			(fill no)
			(layer "F.CrtYd")
		)
		(fp_rect
			(start -0.2794 0.6477)
			(end 0.2794 -0.6477)
			(stroke
				(width 0)
				(type default)
			)
			(fill no)
			(layer "F.Fab")
		)
		(pad "1" smd custom
			(at 0 -0.2794 180)
			(size 0.0762 0.0762)
			(layers "F.Cu" "F.Mask" "F.Paste")
			(net "SAS_HDD_TX5_N")
			(options
				(clearance outline)
				(anchor circle)
			)
			(primitives
				(gr_poly
					(pts
						(arc
							(start 0.1524 -0.127)
							(mid 0.137521 -0.162921)
							(end 0.1016 -0.1778)
						)
						(arc
							(start -0.1016 -0.1778)
							(mid -0.137521 -0.162921)
							(end -0.1524 -0.127)
						)
						(arc
							(start -0.1524 0.127)
							(mid -0.137521 0.162921)
							(end -0.1016 0.1778)
						)
						(arc
							(start 0.1016 0.1778)
							(mid 0.137521 0.162921)
							(end 0.1524 0.127)
						)
					)
					(width 0)
					(fill yes)
				)
			)
		)
		(pad "2" smd custom
			(at 0 0.2794 180)
			(size 0.0762 0.0762)
			(layers "F.Cu" "F.Mask" "F.Paste")
			(net "SAS_EXP_GF_TX_DN9")
			(options
				(clearance outline)
				(anchor circle)
			)
			(primitives
				(gr_poly
					(pts
						(arc
							(start 0.1524 -0.127)
							(mid 0.137521 -0.162921)
							(end 0.1016 -0.1778)
						)
						(arc
							(start -0.1016 -0.1778)
							(mid -0.137521 -0.162921)
							(end -0.1524 -0.127)
						)
						(arc
							(start -0.1524 0.127)
							(mid -0.137521 0.162921)
							(end -0.1016 0.1778)
						)
						(arc
							(start 0.1016 0.1778)
							(mid 0.137521 0.162921)
							(end 0.1524 0.127)
						)
					)
					(width 0)
					(fill yes)
				)
			)
		)
	)
	(footprint ""
		(layer "F.Cu")
		(at 183.134 -50.165 90)
		(property "Reference" "R45"
			(at 0 0 90)
			(layer "F.SilkS")
			(hide yes)
			(effects
				(font
					(size 1.27 1.27)
				)
			)
		)
		(property "Value" "0R2J-2-GP"
			(at 0.064008 -3.993896 90)
			(unlocked yes)
			(layer "F.Fab")
			(hide yes)
			(effects
				(font
					(size 1.016 1.016)
					(thickness 0.1524)
				)
			)
		)
		(property "Device Type" "R402H16"
			(at 0.064008 -5.517896 90)
			(unlocked yes)
			(layer "F.Fab")
			(hide yes)
			(effects
				(font
					(size 1.016 1.016)
					(thickness 0.1524)
				)
			)
		)
		(duplicate_pad_numbers_are_jumpers no)
		(fp_line
			(start 0.508 -0.9398)
			(end -0.508 -0.9398)
			(stroke
				(width 0.1524)
				(type default)
			)
			(layer "F.SilkS")
		)
		(fp_line
			(start -0.508 -0.9398)
			(end -0.508 0.9398)
			(stroke
				(width 0.1524)
				(type default)
			)
			(layer "F.SilkS")
		)
		(fp_rect
			(start -0.508 0.9398)
			(end 0.508 -0.9398)
			(stroke
				(width 0)
				(type default)
			)
			(fill no)
			(layer "F.CrtYd")
		)
		(fp_rect
			(start -0.508 0.9398)
			(end 0.508 -0.9398)
			(stroke
				(width 0)
				(type default)
			)
			(fill no)
			(layer "F.Fab")
		)
		(pad "1" smd custom
			(at 0 -0.4445 90)
			(size 0.1397 0.1397)
			(layers "F.Cu" "F.Mask" "F.Paste")
			(net "PRSNT_CONTROL_BMC")
			(options
				(clearance outline)
				(anchor circle)
			)
			(primitives
				(gr_poly
					(pts
						(arc
							(start -0.1778 -0.2794)
							(mid -0.249642 -0.249642)
							(end -0.2794 -0.1778)
						)
						(arc
							(start -0.2794 0.1778)
							(mid -0.249642 0.249642)
							(end -0.1778 0.2794)
						)
						(arc
							(start 0.1778 0.2794)
							(mid 0.249642 0.249642)
							(end 0.2794 0.1778)
						)
						(arc
							(start 0.2794 -0.1778)
							(mid 0.249642 -0.249642)
							(end 0.1778 -0.2794)
						)
					)
					(width 0)
					(fill yes)
				)
			)
		)
		(pad "2" smd custom
			(at 0 0.4445 90)
			(size 0.1397 0.1397)
			(layers "F.Cu" "F.Mask" "F.Paste")
			(net "PRSNT_AND_2")
			(options
				(clearance outline)
				(anchor circle)
			)
			(primitives
				(gr_poly
					(pts
						(arc
							(start -0.1778 -0.2794)
							(mid -0.249642 -0.249642)
							(end -0.2794 -0.1778)
						)
						(arc
							(start -0.2794 0.1778)
							(mid -0.249642 0.249642)
							(end -0.1778 0.2794)
						)
						(arc
							(start 0.1778 0.2794)
							(mid 0.249642 0.249642)
							(end 0.2794 0.1778)
						)
						(arc
							(start 0.2794 -0.1778)
							(mid 0.249642 -0.249642)
							(end 0.1778 -0.2794)
						)
					)
					(width 0)
					(fill yes)
				)
			)
		)
	)
	(footprint ""
		(layer "F.Cu")
		(at 87.103966 -60.325 90)
		(property "Reference" "SR922"
			(at 0 0 90)
			(layer "F.SilkS")
			(hide yes)
			(effects
				(font
					(size 1.27 1.27)
				)
			)
		)
		(property "Value" "0R2J-2-GP"
			(at 0.064008 -3.993896 90)
			(unlocked yes)
			(layer "F.Fab")
			(hide yes)
			(effects
				(font
					(size 1.016 1.016)
					(thickness 0.1524)
				)
			)
		)
		(property "Device Type" "R402H16"
			(at 0.064008 -5.517896 90)
			(unlocked yes)
			(layer "F.Fab")
			(hide yes)
			(effects
				(font
					(size 1.016 1.016)
					(thickness 0.1524)
				)
			)
		)
		(duplicate_pad_numbers_are_jumpers no)
		(fp_line
			(start 0.508 -0.9398)
			(end -0.508 -0.9398)
			(stroke
				(width 0.1524)
				(type default)
			)
			(layer "F.SilkS")
		)
		(fp_line
			(start -0.508 -0.9398)
			(end -0.508 0.9398)
			(stroke
				(width 0.1524)
				(type default)
			)
			(layer "F.SilkS")
		)
		(fp_rect
			(start -0.508 0.9398)
			(end 0.508 -0.9398)
			(stroke
				(width 0)
				(type default)
			)
			(fill no)
			(layer "F.CrtYd")
		)
		(fp_rect
			(start -0.508 0.9398)
			(end 0.508 -0.9398)
			(stroke
				(width 0)
				(type default)
			)
			(fill no)
			(layer "F.Fab")
		)
		(pad "1" smd custom
			(at 0 -0.4445 90)
			(size 0.1397 0.1397)
			(layers "F.Cu" "F.Mask" "F.Paste")
			(net "REF_CLK")
			(options
				(clearance outline)
				(anchor circle)
			)
			(primitives
				(gr_poly
					(pts
						(arc
							(start -0.1778 -0.2794)
							(mid -0.249642 -0.249642)
							(end -0.2794 -0.1778)
						)
						(arc
							(start -0.2794 0.1778)
							(mid -0.249642 0.249642)
							(end -0.1778 0.2794)
						)
						(arc
							(start 0.1778 0.2794)
							(mid 0.249642 0.249642)
							(end 0.2794 0.1778)
						)
						(arc
							(start 0.2794 -0.1778)
							(mid 0.249642 -0.249642)
							(end 0.1778 -0.2794)
						)
					)
					(width 0)
					(fill yes)
				)
			)
		)
		(pad "2" smd custom
			(at 0 0.4445 90)
			(size 0.1397 0.1397)
			(layers "F.Cu" "F.Mask" "F.Paste")
			(net "IOC_REF_CLK_N")
			(options
				(clearance outline)
				(anchor circle)
			)
			(primitives
				(gr_poly
					(pts
						(arc
							(start -0.1778 -0.2794)
							(mid -0.249642 -0.249642)
							(end -0.2794 -0.1778)
						)
						(arc
							(start -0.2794 0.1778)
							(mid -0.249642 0.249642)
							(end -0.1778 0.2794)
						)
						(arc
							(start 0.1778 0.2794)
							(mid 0.249642 0.249642)
							(end 0.2794 0.1778)
						)
						(arc
							(start 0.2794 -0.1778)
							(mid 0.249642 -0.249642)
							(end 0.1778 -0.2794)
						)
					)
					(width 0)
					(fill yes)
				)
			)
		)
	)
	(footprint ""
		(layer "F.Cu")
		(at 95.358966 -60.325)
		(property "Reference" "STP34"
			(at 0 0 0)
			(layer "F.SilkS")
			(hide yes)
			(effects
				(font
					(size 1.27 1.27)
				)
			)
		)
		(property "Value" "TPAD28"
			(at 0.0127 -1.8034 0)
			(unlocked yes)
			(layer "F.Fab")
			(hide yes)
			(effects
				(font
					(size 1.016 1.016)
					(thickness 0.1524)
				)
			)
		)
		(property "Device Type" "TPAD28"
			(at 0.0127 -3.3274 0)
			(unlocked yes)
			(layer "F.Fab")
			(hide yes)
			(effects
				(font
					(size 1.016 1.016)
					(thickness 0.1524)
				)
			)
		)
		(duplicate_pad_numbers_are_jumpers no)
		(fp_poly
			(pts
				(arc
					(start 0.3556 0)
					(mid -0.3556 0)
					(end 0.3556 0)
				)
			)
			(stroke
				(width 0)
				(type default)
			)
			(fill no)
			(layer "F.CrtYd")
		)
		(fp_poly
			(pts
				(arc
					(start 0.6096 0)
					(mid -0.6096 0)
					(end 0.6096 0)
				)
			)
			(stroke
				(width 0)
				(type default)
			)
			(fill no)
			(layer "F.Fab")
		)
		(pad "1" smd circle
			(at 0 0)
			(size 0.7112 0.7112)
			(layers "F.Cu" "F.Mask" "F.Paste")
			(net "ICE0_TRST#")
		)
	)
	(footprint ""
		(layer "F.Cu")
		(at 82.92719 -59.911488 90)
		(property "Reference" "SC919"
			(at 0 0 90)
			(layer "F.SilkS")
			(hide yes)
			(effects
				(font
					(size 1.27 1.27)
				)
			)
		)
		(property "Value" "SC22U6D3V5MX-2GP"
			(at -0.0762 -6.1214 90)
			(unlocked yes)
			(layer "F.Fab")
			(hide yes)
			(effects
				(font
					(size 1.016 1.016)
					(thickness 0.1524)
				)
			)
		)
		(property "Device Type" "C805H58"
			(at -0.0762 -8.1534 90)
			(unlocked yes)
			(layer "F.Fab")
			(hide yes)
			(effects
				(font
					(size 1.016 1.016)
					(thickness 0.1524)
				)
			)
		)
		(duplicate_pad_numbers_are_jumpers no)
		(fp_line
			(start 0.635 0)
			(end -0.635 0)
			(stroke
				(width 0.508)
				(type default)
			)
			(layer "F.SilkS")
		)
		(fp_rect
			(start -0.9652 1.778)
			(end 0.9652 -1.778)
			(stroke
				(width 0)
				(type default)
			)
			(fill no)
			(layer "F.CrtYd")
		)
		(fp_poly
			(pts
				(xy -0.9652 -1.778) (xy 0.9652 -1.778) (xy 0.9652 1.778) (xy -0.9652 1.778)
			)
			(stroke
				(width 0)
				(type default)
			)
			(fill no)
			(layer "F.Fab")
		)
		(pad "1" smd rect
			(at 0 -0.9652 90)
			(size 1.397 1.143)
			(layers "F.Cu" "F.Mask" "F.Paste")
			(net "SYS_PLL_VDD")
		)
		(pad "2" smd rect
			(at 0 0.9652 90)
			(size 1.397 1.143)
			(layers "F.Cu" "F.Mask" "F.Paste")
			(net "GND")
		)
	)
	(footprint ""
		(layer "F.Cu")
		(at 88.143842 -128.976882)
		(property "Reference" "SC1117"
			(at 0 0 0)
			(layer "F.SilkS")
			(hide yes)
			(effects
				(font
					(size 1.27 1.27)
				)
			)
		)
		(property "Value" "SCD1U16V2KX-3GP"
			(at 1.1811 -2.7051 0)
			(unlocked yes)
			(layer "F.Fab")
			(hide yes)
			(effects
				(font
					(size 1.016 1.016)
					(thickness 0.1524)
				)
			)
		)
		(property "Device Type" "C402H22"
			(at 1.1811 -4.2291 0)
			(unlocked yes)
			(layer "F.Fab")
			(hide yes)
			(effects
				(font
					(size 1.016 1.016)
					(thickness 0.1524)
				)
			)
		)
		(duplicate_pad_numbers_are_jumpers no)
		(fp_rect
			(start -0.4318 0.9525)
			(end 0.4318 -0.9525)
			(stroke
				(width 0)
				(type default)
			)
			(fill no)
			(layer "F.CrtYd")
		)
		(fp_rect
			(start -0.4318 0.9525)
			(end 0.4318 -0.9525)
			(stroke
				(width 0)
				(type default)
			)
			(fill no)
			(layer "F.Fab")
		)
		(pad "1" smd custom
			(at 0 -0.4445)
			(size 0.1524 0.1524)
			(layers "F.Cu" "F.Mask" "F.Paste")
			(net "P1V8_E")
			(options
				(clearance outline)
				(anchor circle)
			)
			(primitives
				(gr_poly
					(pts
						(arc
							(start 0.3048 -0.2032)
							(mid 0.275042 -0.275042)
							(end 0.2032 -0.3048)
						)
						(arc
							(start -0.2032 -0.3048)
							(mid -0.275042 -0.275042)
							(end -0.3048 -0.2032)
						)
						(arc
							(start -0.3048 0.2032)
							(mid -0.275042 0.275042)
							(end -0.2032 0.3048)
						)
						(arc
							(start 0.2032 0.3048)
							(mid 0.275042 0.275042)
							(end 0.3048 0.2032)
						)
					)
					(width 0)
					(fill yes)
				)
			)
		)
		(pad "2" smd custom
			(at 0 0.4445)
			(size 0.1524 0.1524)
			(layers "F.Cu" "F.Mask" "F.Paste")
			(net "GND")
			(options
				(clearance outline)
				(anchor circle)
			)
			(primitives
				(gr_poly
					(pts
						(arc
							(start 0.3048 -0.2032)
							(mid 0.275042 -0.275042)
							(end 0.2032 -0.3048)
						)
						(arc
							(start -0.2032 -0.3048)
							(mid -0.275042 -0.275042)
							(end -0.3048 -0.2032)
						)
						(arc
							(start -0.3048 0.2032)
							(mid -0.275042 0.275042)
							(end -0.2032 0.3048)
						)
						(arc
							(start 0.2032 0.3048)
							(mid 0.275042 0.275042)
							(end 0.3048 0.2032)
						)
					)
					(width 0)
					(fill yes)
				)
			)
		)
	)
	(footprint ""
		(layer "F.Cu")
		(at 215.773 -182.88 -90)
		(property "Reference" "C305"
			(at 0 0 270)
			(layer "F.SilkS")
			(hide yes)
			(effects
				(font
					(size 1.27 1.27)
				)
			)
		)
		(property "Value" "SC1U10V3KX-4GP-U"
			(at 0 -2.8194 270)
			(unlocked yes)
			(layer "F.Fab")
			(hide yes)
			(effects
				(font
					(size 1.016 1.016)
					(thickness 0.1524)
				)
			)
		)
		(property "Device Type" "C603H36"
			(at 0 -4.3434 270)
			(unlocked yes)
			(layer "F.Fab")
			(hide yes)
			(effects
				(font
					(size 1.016 1.016)
					(thickness 0.1524)
				)
			)
		)
		(duplicate_pad_numbers_are_jumpers no)
		(fp_line
			(start 0.508 0)
			(end -0.508 0)
			(stroke
				(width 0.2032)
				(type default)
			)
			(layer "F.SilkS")
		)
		(fp_rect
			(start -0.5842 1.3335)
			(end 0.5842 -1.3335)
			(stroke
				(width 0)
				(type default)
			)
			(fill no)
			(layer "F.CrtYd")
		)
		(fp_rect
			(start -0.5842 1.3335)
			(end 0.5842 -1.3335)
			(stroke
				(width 0)
				(type default)
			)
			(fill no)
			(layer "F.Fab")
		)
		(pad "1" smd custom
			(at 0 -0.762 270)
			(size 0.2159 0.2159)
			(layers "F.Cu" "F.Mask" "F.Paste")
			(net "HB_A_IN_EXP")
			(options
				(clearance outline)
				(anchor circle)
			)
			(primitives
				(gr_poly
					(pts
						(arc
							(start -0.3302 -0.4318)
							(mid -0.402042 -0.402042)
							(end -0.4318 -0.3302)
						)
						(arc
							(start -0.4318 0.3302)
							(mid -0.402042 0.402042)
							(end -0.3302 0.4318)
						)
						(arc
							(start 0.3302 0.4318)
							(mid 0.402042 0.402042)
							(end 0.4318 0.3302)
						)
						(arc
							(start 0.4318 -0.3302)
							(mid 0.402042 -0.402042)
							(end 0.3302 -0.4318)
						)
					)
					(width 0)
					(fill yes)
				)
			)
		)
		(pad "2" smd custom
			(at 0 0.762 270)
			(size 0.2159 0.2159)
			(layers "F.Cu" "F.Mask" "F.Paste")
			(net "GND")
			(options
				(clearance outline)
				(anchor circle)
			)
			(primitives
				(gr_poly
					(pts
						(arc
							(start -0.3302 -0.4318)
							(mid -0.402042 -0.402042)
							(end -0.4318 -0.3302)
						)
						(arc
							(start -0.4318 0.3302)
							(mid -0.402042 0.402042)
							(end -0.3302 0.4318)
						)
						(arc
							(start 0.3302 0.4318)
							(mid 0.402042 0.402042)
							(end 0.4318 0.3302)
						)
						(arc
							(start 0.4318 -0.3302)
							(mid 0.402042 -0.402042)
							(end 0.3302 -0.4318)
						)
					)
					(width 0)
					(fill yes)
				)
			)
		)
	)
	(footprint ""
		(layer "F.Cu")
		(at 189.611 -26.67)
		(property "Reference" "TP127"
			(at 0 0 0)
			(layer "F.SilkS")
			(hide yes)
			(effects
				(font
					(size 1.27 1.27)
				)
			)
		)
		(property "Value" "TPAD28"
			(at 0.0127 -1.8034 0)
			(unlocked yes)
			(layer "F.Fab")
			(hide yes)
			(effects
				(font
					(size 1.016 1.016)
					(thickness 0.1524)
				)
			)
		)
		(property "Device Type" "TPAD28"
			(at 0.0127 -3.3274 0)
			(unlocked yes)
			(layer "F.Fab")
			(hide yes)
			(effects
				(font
					(size 1.016 1.016)
					(thickness 0.1524)
				)
			)
		)
		(duplicate_pad_numbers_are_jumpers no)
		(fp_poly
			(pts
				(arc
					(start 0.3556 0)
					(mid -0.3556 0)
					(end 0.3556 0)
				)
			)
			(stroke
				(width 0)
				(type default)
			)
			(fill no)
			(layer "F.CrtYd")
		)
		(fp_poly
			(pts
				(arc
					(start 0.6096 0)
					(mid -0.6096 0)
					(end 0.6096 0)
				)
			)
			(stroke
				(width 0)
				(type default)
			)
			(fill no)
			(layer "F.Fab")
		)
		(pad "1" smd circle
			(at 0 0)
			(size 0.7112 0.7112)
			(layers "F.Cu" "F.Mask" "F.Paste")
			(net "NC_PHY_RXC")
		)
	)
)
